(kicad_pcb
	(version 20260206)
	(generator "pcbnew")
	(generator_version "10.0")
	(general
		(thickness 1.6)
		(legacy_teardrops no)
	)
	(paper "A4")
	(title_block
		(title "03242023_DA0F0TMBIJ0_F0T_Motherboard_J_brd_V01_OCP.brd")
		(comment 1 "Grand Teton / footprints 3686-3691 of 6105")
	)
	(layers
		(0 "F.Cu" signal "TOP")
		(4 "In1.Cu" signal "GND")
		(6 "In2.Cu" signal "IN1")
		(8 "In3.Cu" signal "GND1")
		(10 "In4.Cu" signal "IN2")
		(12 "In5.Cu" signal "GND2")
		(14 "In6.Cu" signal "IN3")
		(16 "In7.Cu" signal "GND3")
		(18 "In8.Cu" signal "VCC")
		(20 "In9.Cu" signal "VCC1")
		(22 "In10.Cu" signal "GND4")
		(24 "In11.Cu" signal "IN4")
		(26 "In12.Cu" signal "GND5")
		(28 "In13.Cu" signal "IN5")
		(30 "In14.Cu" signal "GND6")
		(32 "In15.Cu" signal "IN6")
		(34 "In16.Cu" signal "GND7")
		(2 "B.Cu" signal "BOTTOM")
		(9 "F.Adhes" user "F.Adhesive")
		(11 "B.Adhes" user "B.Adhesive")
		(13 "F.Paste" user "Package Geometry/Pastemask Top")
		(15 "B.Paste" user "Package Geometry/Pastemask Bottom")
		(5 "F.SilkS" user "Ref Des/Silkscreen Top")
		(7 "B.SilkS" user "Ref Des/Silkscreen Bottom")
		(1 "F.Mask" user "Board Geometry/Soldermask Top")
		(3 "B.Mask" user "Board Geometry/Soldermask Bottom")
		(17 "Dwgs.User" user "User.Drawings")
		(19 "Cmts.User" user "User.Comments")
		(21 "Eco1.User" user "User.Eco1")
		(23 "Eco2.User" user "User.Eco2")
		(25 "Edge.Cuts" user "Board Geometry/Outline")
		(27 "Margin" user)
		(31 "F.CrtYd" user "Package Geometry/Place Bound Top")
		(29 "B.CrtYd" user "Package Geometry/Place Bound Bottom")
		(35 "F.Fab" user "Ref Des/Assembly Top")
		(33 "B.Fab" user "Ref Des/Assembly Bottom")
	)
	(footprint ""
		(layer "F.Cu")
		(at 50.437542 -149.575266)
		(property "Reference" "PC447"
			(at 0 0 0)
			(layer "F.SilkS")
			(hide yes)
			(effects
				(font
					(size 1.27 1.27)
				)
			)
		)
		(property "Value" ""
			(at 0 0 0)
			(layer "F.Fab")
			(effects
				(font
					(size 1.27 1.27)
				)
			)
		)
		(duplicate_pad_numbers_are_jumpers no)
		(fp_line
			(start -0.7874 -0.4064)
			(end 0.7874 -0.4064)
			(stroke
				(width 0.1524)
				(type default)
			)
			(layer "F.SilkS")
		)
		(fp_line
			(start -0.7874 0.4064)
			(end -0.7874 -0.4064)
			(stroke
				(width 0.1524)
				(type default)
			)
			(layer "F.SilkS")
		)
		(fp_line
			(start 0.7874 -0.4064)
			(end 0.7874 0.4064)
			(stroke
				(width 0.1524)
				(type default)
			)
			(layer "F.SilkS")
		)
		(fp_line
			(start 0.7874 0.4064)
			(end -0.7874 0.4064)
			(stroke
				(width 0.1524)
				(type default)
			)
			(layer "F.SilkS")
		)
		(fp_line
			(start -0.67945 -0.305054)
			(end -0.12065 -0.305054)
			(stroke
				(width 0.1)
				(type default)
			)
			(layer "F.Fab")
		)
		(fp_line
			(start -0.67945 0.3048)
			(end -0.67945 -0.305054)
			(stroke
				(width 0.1)
				(type default)
			)
			(layer "F.Fab")
		)
		(fp_line
			(start -0.12065 -0.305054)
			(end -0.12065 -0.2794)
			(stroke
				(width 0.1)
				(type default)
			)
			(layer "F.Fab")
		)
		(fp_line
			(start -0.12065 -0.2794)
			(end 0.12065 -0.2794)
			(stroke
				(width 0.1)
				(type default)
			)
			(layer "F.Fab")
		)
		(fp_line
			(start -0.12065 0.2794)
			(end -0.12065 0.3048)
			(stroke
				(width 0.1)
				(type default)
			)
			(layer "F.Fab")
		)
		(fp_line
			(start -0.12065 0.3048)
			(end -0.67945 0.3048)
			(stroke
				(width 0.1)
				(type default)
			)
			(layer "F.Fab")
		)
		(fp_line
			(start 0.120396 0.2794)
			(end -0.12065 0.2794)
			(stroke
				(width 0.1)
				(type default)
			)
			(layer "F.Fab")
		)
		(fp_line
			(start 0.120396 0.3048)
			(end 0.120396 0.2794)
			(stroke
				(width 0.1)
				(type default)
			)
			(layer "F.Fab")
		)
		(fp_line
			(start 0.12065 -0.3048)
			(end 0.67945 -0.3048)
			(stroke
				(width 0.1)
				(type default)
			)
			(layer "F.Fab")
		)
		(fp_line
			(start 0.12065 -0.2794)
			(end 0.12065 -0.3048)
			(stroke
				(width 0.1)
				(type default)
			)
			(layer "F.Fab")
		)
		(fp_line
			(start 0.67945 -0.3048)
			(end 0.67945 0.3048)
			(stroke
				(width 0.1)
				(type default)
			)
			(layer "F.Fab")
		)
		(fp_line
			(start 0.67945 0.3048)
			(end 0.120396 0.3048)
			(stroke
				(width 0.1)
				(type default)
			)
			(layer "F.Fab")
		)
		(pad "1" smd circle
			(at -0.40005 0)
			(size 0 0)
			(layers "F.Cu" "F.Mask" "F.Paste")
			(net "SW_PVCCINFAON_CPU1_BOOT2_R")
		)
		(pad "2" smd circle
			(at 0.40005 0)
			(size 0 0)
			(layers "F.Cu" "F.Mask" "F.Paste")
			(net "SW_PVCCINFAON_CPU1_BOOTR2")
		)
	)
	(footprint ""
		(layer "F.Cu")
		(at 278.246078 -417.2839 -90)
		(property "Reference" "R4673"
			(at 0 0 270)
			(layer "F.SilkS")
			(hide yes)
			(effects
				(font
					(size 1.27 1.27)
				)
			)
		)
		(property "Value" ""
			(at 0 0 270)
			(layer "F.Fab")
			(effects
				(font
					(size 1.27 1.27)
				)
			)
		)
		(duplicate_pad_numbers_are_jumpers no)
		(fp_line
			(start -0.7874 0.4064)
			(end -0.7874 -0.4064)
			(stroke
				(width 0.1524)
				(type default)
			)
			(layer "F.SilkS")
		)
		(fp_line
			(start 0.7874 0.4064)
			(end -0.7874 0.4064)
			(stroke
				(width 0.1524)
				(type default)
			)
			(layer "F.SilkS")
		)
		(fp_line
			(start -0.7874 -0.4064)
			(end 0.7874 -0.4064)
			(stroke
				(width 0.1524)
				(type default)
			)
			(layer "F.SilkS")
		)
		(fp_line
			(start 0.7874 -0.4064)
			(end 0.7874 0.4064)
			(stroke
				(width 0.1524)
				(type default)
			)
			(layer "F.SilkS")
		)
		(fp_line
			(start -0.67945 0.3048)
			(end -0.67945 -0.305054)
			(stroke
				(width 0.1)
				(type default)
			)
			(layer "F.Fab")
		)
		(fp_line
			(start -0.12065 0.3048)
			(end -0.67945 0.3048)
			(stroke
				(width 0.1)
				(type default)
			)
			(layer "F.Fab")
		)
		(fp_line
			(start 0.120396 0.3048)
			(end 0.120396 0.2794)
			(stroke
				(width 0.1)
				(type default)
			)
			(layer "F.Fab")
		)
		(fp_line
			(start 0.67945 0.3048)
			(end 0.120396 0.3048)
			(stroke
				(width 0.1)
				(type default)
			)
			(layer "F.Fab")
		)
		(fp_line
			(start -0.12065 0.2794)
			(end -0.12065 0.3048)
			(stroke
				(width 0.1)
				(type default)
			)
			(layer "F.Fab")
		)
		(fp_line
			(start 0.120396 0.2794)
			(end -0.12065 0.2794)
			(stroke
				(width 0.1)
				(type default)
			)
			(layer "F.Fab")
		)
		(fp_line
			(start -0.12065 -0.2794)
			(end 0.12065 -0.2794)
			(stroke
				(width 0.1)
				(type default)
			)
			(layer "F.Fab")
		)
		(fp_line
			(start 0.12065 -0.2794)
			(end 0.12065 -0.3048)
			(stroke
				(width 0.1)
				(type default)
			)
			(layer "F.Fab")
		)
		(fp_line
			(start 0.12065 -0.3048)
			(end 0.67945 -0.3048)
			(stroke
				(width 0.1)
				(type default)
			)
			(layer "F.Fab")
		)
		(fp_line
			(start 0.67945 -0.3048)
			(end 0.67945 0.3048)
			(stroke
				(width 0.1)
				(type default)
			)
			(layer "F.Fab")
		)
		(fp_line
			(start -0.67945 -0.305054)
			(end -0.12065 -0.305054)
			(stroke
				(width 0.1)
				(type default)
			)
			(layer "F.Fab")
		)
		(fp_line
			(start -0.12065 -0.305054)
			(end -0.12065 -0.2794)
			(stroke
				(width 0.1)
				(type default)
			)
			(layer "F.Fab")
		)
		(pad "1" smd circle
			(at -0.40005 0 270)
			(size 0 0)
			(layers "F.Cu" "F.Mask" "F.Paste")
			(net "A_HSC_LOW_GATE")
		)
		(pad "2" smd circle
			(at 0.40005 0 270)
			(size 0 0)
			(layers "F.Cu" "F.Mask" "F.Paste")
			(net "GND")
		)
	)
	(footprint ""
		(layer "F.Cu")
		(at 374.16359 -66.898012)
		(property "Reference" "R755"
			(at 0 0 0)
			(layer "F.SilkS")
			(hide yes)
			(effects
				(font
					(size 1.27 1.27)
				)
			)
		)
		(property "Value" ""
			(at 0 0 0)
			(layer "F.Fab")
			(effects
				(font
					(size 1.27 1.27)
				)
			)
		)
		(duplicate_pad_numbers_are_jumpers no)
		(fp_line
			(start -0.7874 -0.4064)
			(end 0.7874 -0.4064)
			(stroke
				(width 0.1524)
				(type default)
			)
			(layer "F.SilkS")
		)
		(fp_line
			(start -0.7874 0.4064)
			(end -0.7874 -0.4064)
			(stroke
				(width 0.1524)
				(type default)
			)
			(layer "F.SilkS")
		)
		(fp_line
			(start 0.7874 -0.4064)
			(end 0.7874 0.4064)
			(stroke
				(width 0.1524)
				(type default)
			)
			(layer "F.SilkS")
		)
		(fp_line
			(start 0.7874 0.4064)
			(end -0.7874 0.4064)
			(stroke
				(width 0.1524)
				(type default)
			)
			(layer "F.SilkS")
		)
		(fp_line
			(start -0.67945 -0.305054)
			(end -0.12065 -0.305054)
			(stroke
				(width 0.1)
				(type default)
			)
			(layer "F.Fab")
		)
		(fp_line
			(start -0.67945 0.3048)
			(end -0.67945 -0.305054)
			(stroke
				(width 0.1)
				(type default)
			)
			(layer "F.Fab")
		)
		(fp_line
			(start -0.12065 -0.305054)
			(end -0.12065 -0.2794)
			(stroke
				(width 0.1)
				(type default)
			)
			(layer "F.Fab")
		)
		(fp_line
			(start -0.12065 -0.2794)
			(end 0.12065 -0.2794)
			(stroke
				(width 0.1)
				(type default)
			)
			(layer "F.Fab")
		)
		(fp_line
			(start -0.12065 0.2794)
			(end -0.12065 0.3048)
			(stroke
				(width 0.1)
				(type default)
			)
			(layer "F.Fab")
		)
		(fp_line
			(start -0.12065 0.3048)
			(end -0.67945 0.3048)
			(stroke
				(width 0.1)
				(type default)
			)
			(layer "F.Fab")
		)
		(fp_line
			(start 0.120396 0.2794)
			(end -0.12065 0.2794)
			(stroke
				(width 0.1)
				(type default)
			)
			(layer "F.Fab")
		)
		(fp_line
			(start 0.120396 0.3048)
			(end 0.120396 0.2794)
			(stroke
				(width 0.1)
				(type default)
			)
			(layer "F.Fab")
		)
		(fp_line
			(start 0.12065 -0.3048)
			(end 0.67945 -0.3048)
			(stroke
				(width 0.1)
				(type default)
			)
			(layer "F.Fab")
		)
		(fp_line
			(start 0.12065 -0.2794)
			(end 0.12065 -0.3048)
			(stroke
				(width 0.1)
				(type default)
			)
			(layer "F.Fab")
		)
		(fp_line
			(start 0.67945 -0.3048)
			(end 0.67945 0.3048)
			(stroke
				(width 0.1)
				(type default)
			)
			(layer "F.Fab")
		)
		(fp_line
			(start 0.67945 0.3048)
			(end 0.120396 0.3048)
			(stroke
				(width 0.1)
				(type default)
			)
			(layer "F.Fab")
		)
		(pad "1" smd circle
			(at -0.40005 0)
			(size 0 0)
			(layers "F.Cu" "F.Mask" "F.Paste")
			(net "JTAG_DBP_PREQ_N")
		)
		(pad "2" smd circle
			(at 0.40005 0)
			(size 0 0)
			(layers "F.Cu" "F.Mask" "F.Paste")
			(net "H_DBP_PREQ_N_PCH")
		)
	)
	(footprint ""
		(layer "F.Cu")
		(at 152.09393 -36.741608 -90)
		(property "Reference" "C2327"
			(at 0 0 270)
			(layer "F.SilkS")
			(hide yes)
			(effects
				(font
					(size 1.27 1.27)
				)
			)
		)
		(property "Value" ""
			(at 0 0 270)
			(layer "F.Fab")
			(effects
				(font
					(size 1.27 1.27)
				)
			)
		)
		(duplicate_pad_numbers_are_jumpers no)
		(fp_line
			(start -0.7874 0.4064)
			(end -0.7874 -0.4064)
			(stroke
				(width 0.1524)
				(type default)
			)
			(layer "F.SilkS")
		)
		(fp_line
			(start 0.7874 0.4064)
			(end -0.7874 0.4064)
			(stroke
				(width 0.1524)
				(type default)
			)
			(layer "F.SilkS")
		)
		(fp_line
			(start -0.7874 -0.4064)
			(end 0.7874 -0.4064)
			(stroke
				(width 0.1524)
				(type default)
			)
			(layer "F.SilkS")
		)
		(fp_line
			(start 0.7874 -0.4064)
			(end 0.7874 0.4064)
			(stroke
				(width 0.1524)
				(type default)
			)
			(layer "F.SilkS")
		)
		(fp_line
			(start -0.67945 0.3048)
			(end -0.67945 -0.305054)
			(stroke
				(width 0.1)
				(type default)
			)
			(layer "F.Fab")
		)
		(fp_line
			(start -0.12065 0.3048)
			(end -0.67945 0.3048)
			(stroke
				(width 0.1)
				(type default)
			)
			(layer "F.Fab")
		)
		(fp_line
			(start 0.120396 0.3048)
			(end 0.120396 0.2794)
			(stroke
				(width 0.1)
				(type default)
			)
			(layer "F.Fab")
		)
		(fp_line
			(start 0.67945 0.3048)
			(end 0.120396 0.3048)
			(stroke
				(width 0.1)
				(type default)
			)
			(layer "F.Fab")
		)
		(fp_line
			(start -0.12065 0.2794)
			(end -0.12065 0.3048)
			(stroke
				(width 0.1)
				(type default)
			)
			(layer "F.Fab")
		)
		(fp_line
			(start 0.120396 0.2794)
			(end -0.12065 0.2794)
			(stroke
				(width 0.1)
				(type default)
			)
			(layer "F.Fab")
		)
		(fp_line
			(start -0.12065 -0.2794)
			(end 0.12065 -0.2794)
			(stroke
				(width 0.1)
				(type default)
			)
			(layer "F.Fab")
		)
		(fp_line
			(start 0.12065 -0.2794)
			(end 0.12065 -0.3048)
			(stroke
				(width 0.1)
				(type default)
			)
			(layer "F.Fab")
		)
		(fp_line
			(start 0.12065 -0.3048)
			(end 0.67945 -0.3048)
			(stroke
				(width 0.1)
				(type default)
			)
			(layer "F.Fab")
		)
		(fp_line
			(start 0.67945 -0.3048)
			(end 0.67945 0.3048)
			(stroke
				(width 0.1)
				(type default)
			)
			(layer "F.Fab")
		)
		(fp_line
			(start -0.67945 -0.305054)
			(end -0.12065 -0.305054)
			(stroke
				(width 0.1)
				(type default)
			)
			(layer "F.Fab")
		)
		(fp_line
			(start -0.12065 -0.305054)
			(end -0.12065 -0.2794)
			(stroke
				(width 0.1)
				(type default)
			)
			(layer "F.Fab")
		)
		(pad "1" smd circle
			(at -0.40005 0 270)
			(size 0 0)
			(layers "F.Cu" "F.Mask" "F.Paste")
			(net "USB_HUB_2_XTAL_OUT")
		)
		(pad "2" smd circle
			(at 0.40005 0 270)
			(size 0 0)
			(layers "F.Cu" "F.Mask" "F.Paste")
			(net "GND")
		)
	)
	(footprint ""
		(layer "F.Cu")
		(at 167.386 -23.713948 -90)
		(property "Reference" "R148"
			(at 0 0 270)
			(layer "F.SilkS")
			(hide yes)
			(effects
				(font
					(size 1.27 1.27)
				)
			)
		)
		(property "Value" ""
			(at 0 0 270)
			(layer "F.Fab")
			(effects
				(font
					(size 1.27 1.27)
				)
			)
		)
		(duplicate_pad_numbers_are_jumpers no)
		(fp_line
			(start -0.7874 0.4064)
			(end -0.7874 -0.4064)
			(stroke
				(width 0.1524)
				(type default)
			)
			(layer "F.SilkS")
		)
		(fp_line
			(start 0.7874 0.4064)
			(end -0.7874 0.4064)
			(stroke
				(width 0.1524)
				(type default)
			)
			(layer "F.SilkS")
		)
		(fp_line
			(start -0.7874 -0.4064)
			(end 0.7874 -0.4064)
			(stroke
				(width 0.1524)
				(type default)
			)
			(layer "F.SilkS")
		)
		(fp_line
			(start 0.7874 -0.4064)
			(end 0.7874 0.4064)
			(stroke
				(width 0.1524)
				(type default)
			)
			(layer "F.SilkS")
		)
		(fp_line
			(start -0.67945 0.3048)
			(end -0.67945 -0.305054)
			(stroke
				(width 0.1)
				(type default)
			)
			(layer "F.Fab")
		)
		(fp_line
			(start -0.12065 0.3048)
			(end -0.67945 0.3048)
			(stroke
				(width 0.1)
				(type default)
			)
			(layer "F.Fab")
		)
		(fp_line
			(start 0.120396 0.3048)
			(end 0.120396 0.2794)
			(stroke
				(width 0.1)
				(type default)
			)
			(layer "F.Fab")
		)
		(fp_line
			(start 0.67945 0.3048)
			(end 0.120396 0.3048)
			(stroke
				(width 0.1)
				(type default)
			)
			(layer "F.Fab")
		)
		(fp_line
			(start -0.12065 0.2794)
			(end -0.12065 0.3048)
			(stroke
				(width 0.1)
				(type default)
			)
			(layer "F.Fab")
		)
		(fp_line
			(start 0.120396 0.2794)
			(end -0.12065 0.2794)
			(stroke
				(width 0.1)
				(type default)
			)
			(layer "F.Fab")
		)
		(fp_line
			(start -0.12065 -0.2794)
			(end 0.12065 -0.2794)
			(stroke
				(width 0.1)
				(type default)
			)
			(layer "F.Fab")
		)
		(fp_line
			(start 0.12065 -0.2794)
			(end 0.12065 -0.3048)
			(stroke
				(width 0.1)
				(type default)
			)
			(layer "F.Fab")
		)
		(fp_line
			(start 0.12065 -0.3048)
			(end 0.67945 -0.3048)
			(stroke
				(width 0.1)
				(type default)
			)
			(layer "F.Fab")
		)
		(fp_line
			(start 0.67945 -0.3048)
			(end 0.67945 0.3048)
			(stroke
				(width 0.1)
				(type default)
			)
			(layer "F.Fab")
		)
		(fp_line
			(start -0.67945 -0.305054)
			(end -0.12065 -0.305054)
			(stroke
				(width 0.1)
				(type default)
			)
			(layer "F.Fab")
		)
		(fp_line
			(start -0.12065 -0.305054)
			(end -0.12065 -0.2794)
			(stroke
				(width 0.1)
				(type default)
			)
			(layer "F.Fab")
		)
		(pad "1" smd circle
			(at -0.40005 0 270)
			(size 0 0)
			(layers "F.Cu" "F.Mask" "F.Paste")
			(net "PECI_BMC_R")
		)
		(pad "2" smd circle
			(at 0.40005 0 270)
			(size 0 0)
			(layers "F.Cu" "F.Mask" "F.Paste")
			(net "GND")
		)
	)
	(footprint ""
		(layer "F.Cu")
		(at 427.176438 -181.53507 90)
		(property "Reference" "PC1273"
			(at 0 0 90)
			(layer "F.SilkS")
			(hide yes)
			(effects
				(font
					(size 1.27 1.27)
				)
			)
		)
		(property "Value" ""
			(at 0 0 90)
			(layer "F.Fab")
			(effects
				(font
					(size 1.27 1.27)
				)
			)
		)
		(duplicate_pad_numbers_are_jumpers no)
		(fp_line
			(start 1.524 -0.762)
			(end 1.524 0.762)
			(stroke
				(width 0.1524)
				(type default)
			)
			(layer "F.SilkS")
		)
		(fp_line
			(start -1.524 -0.762)
			(end 1.524 -0.762)
			(stroke
				(width 0.1524)
				(type default)
			)
			(layer "F.SilkS")
		)
		(fp_line
			(start 1.524 0.762)
			(end -1.524 0.762)
			(stroke
				(width 0.1524)
				(type default)
			)
			(layer "F.SilkS")
		)
		(fp_line
			(start -1.524 0.762)
			(end -1.524 -0.762)
			(stroke
				(width 0.1524)
				(type default)
			)
			(layer "F.SilkS")
		)
		(fp_line
			(start 1.1049 -0.724916)
			(end -1.1049 -0.724916)
			(stroke
				(width 0.1)
				(type default)
			)
			(layer "F.Fab")
		)
		(fp_line
			(start -1.1049 -0.724916)
			(end -1.1049 0.724916)
			(stroke
				(width 0.1)
				(type default)
			)
			(layer "F.Fab")
		)
		(fp_line
			(start 1.1049 0.724916)
			(end 1.1049 -0.724916)
			(stroke
				(width 0.1)
				(type default)
			)
			(layer "F.Fab")
		)
		(fp_line
			(start -1.1049 0.724916)
			(end 1.1049 0.724916)
			(stroke
				(width 0.1)
				(type default)
			)
			(layer "F.Fab")
		)
		(pad "1" smd rect
			(at -0.889 0 270)
			(size 1.016 1.27)
			(layers "F.Cu" "F.Mask" "F.Paste")
			(net "SW_P12V_PVCCINFAON_CPU0_FLT")
		)
		(pad "2" smd rect
			(at 0.889 0 270)
			(size 1.016 1.27)
			(layers "F.Cu" "F.Mask" "F.Paste")
			(net "GND")
		)
	)
)
